# T6G (Grand Teton) — schematic netlist excerpt (pin names and nets, part order shuffled) for the footprints in the layout excerpt that follows; sources: Cadence DE-HDL packaged netlist, KiCad conversion of 04192023_DAF0TMB3IC0_F0TG_MB_C_brd_V02_OCP.brd

C552  Q_CAP  0.1UF 25V 10% X7R  pkg 0402  page 84 : A = P1V8_AUX ; B = GND
R749  Q_RES  10K 1% CHIP  pkg 0201LF  page 331 : A = RST_RT_CPU1_P1_PERST_R_N ; B = GND
R6734  Q_RES  1K 1% CHIP  pkg 0201LF  page 185 : A = P1V8_CPU1_RT_1D ; B = SMB_RT_CPU1_P1_ROM_R_SCL

(kicad_pcb
	(version 20260206)
	(generator "pcbnew")
	(generator_version "10.0")
	(general
		(thickness 1.6)
		(legacy_teardrops no)
	)
	(paper "A4")
	(title_block
		(title "04192023_DAF0TMB3IC0_F0TG_MB_C_brd_V02_OCP.brd")
		(comment 1 "Grand Teton / footprints 4442-4444 of 8354")
	)
	(layers
		(0 "F.Cu" signal "TOP")
		(4 "In1.Cu" signal "GND")
		(6 "In2.Cu" signal "IN1")
		(8 "In3.Cu" signal "GND1")
		(10 "In4.Cu" signal "IN2")
		(12 "In5.Cu" signal "GND2")
		(14 "In6.Cu" signal "IN3")
		(16 "In7.Cu" signal "GND3")
		(18 "In8.Cu" signal "VCC")
		(20 "In9.Cu" signal "VCC1")
		(22 "In10.Cu" signal "GND4")
		(24 "In11.Cu" signal "IN4")
		(26 "In12.Cu" signal "GND5")
		(28 "In13.Cu" signal "IN5")
		(30 "In14.Cu" signal "GND6")
		(32 "In15.Cu" signal "IN6")
		(34 "In16.Cu" signal "GND7")
		(2 "B.Cu" signal "BOTTOM")
		(9 "F.Adhes" user "F.Adhesive")
		(11 "B.Adhes" user "B.Adhesive")
		(13 "F.Paste" user "Package Geometry/Pastemask Top")
		(15 "B.Paste" user "Package Geometry/Pastemask Bottom")
		(5 "F.SilkS" user "Ref Des/Silkscreen Top")
		(7 "B.SilkS" user "Ref Des/Silkscreen Bottom")
		(1 "F.Mask" user "Board Geometry/Soldermask Top")
		(3 "B.Mask" user "Board Geometry/Soldermask Bottom")
		(17 "Dwgs.User" user "User.Drawings")
		(19 "Cmts.User" user "User.Comments")
		(21 "Eco1.User" user "User.Eco1")
		(23 "Eco2.User" user "User.Eco2")
		(25 "Edge.Cuts" user "Board Geometry/Outline")
		(27 "Margin" user)
		(31 "F.CrtYd" user "Package Geometry/Place Bound Top")
		(29 "B.CrtYd" user "Package Geometry/Place Bound Bottom")
		(35 "F.Fab" user "Ref Des/Assembly Top")
		(33 "B.Fab" user "Ref Des/Assembly Bottom")
	)
	(footprint ""
		(layer "F.Cu")
		(at 155.829 -111.76)
		(property "Reference" "C552"
			(at 0 0 0)
			(layer "F.SilkS")
			(hide yes)
			(effects
				(font
					(size 1.27 1.27)
				)
			)
		)
		(property "Value" ""
			(at 0 0 0)
			(layer "F.Fab")
			(effects
				(font
					(size 1.27 1.27)
				)
			)
		)
		(duplicate_pad_numbers_are_jumpers no)
		(fp_line
			(start -0.7874 -0.4064)
			(end 0.7874 -0.4064)
			(stroke
				(width 0.1524)
				(type default)
			)
			(layer "F.SilkS")
		)
		(fp_line
			(start -0.7874 0.4064)
			(end -0.7874 -0.4064)
			(stroke
				(width 0.1524)
				(type default)
			)
			(layer "F.SilkS")
		)
		(fp_line
			(start 0.7874 -0.4064)
			(end 0.7874 0.4064)
			(stroke
				(width 0.1524)
				(type default)
			)
			(layer "F.SilkS")
		)
		(fp_line
			(start 0.7874 0.4064)
			(end -0.7874 0.4064)
			(stroke
				(width 0.1524)
				(type default)
			)
			(layer "F.SilkS")
		)
		(fp_line
			(start -0.67945 -0.305054)
			(end -0.12065 -0.305054)
			(stroke
				(width 0.1)
				(type default)
			)
			(layer "F.Fab")
		)
		(fp_line
			(start -0.67945 0.3048)
			(end -0.67945 -0.305054)
			(stroke
				(width 0.1)
				(type default)
			)
			(layer "F.Fab")
		)
		(fp_line
			(start -0.12065 -0.305054)
			(end -0.12065 -0.2794)
			(stroke
				(width 0.1)
				(type default)
			)
			(layer "F.Fab")
		)
		(fp_line
			(start -0.12065 -0.2794)
			(end 0.12065 -0.2794)
			(stroke
				(width 0.1)
				(type default)
			)
			(layer "F.Fab")
		)
		(fp_line
			(start -0.12065 0.2794)
			(end -0.12065 0.3048)
			(stroke
				(width 0.1)
				(type default)
			)
			(layer "F.Fab")
		)
		(fp_line
			(start -0.12065 0.3048)
			(end -0.67945 0.3048)
			(stroke
				(width 0.1)
				(type default)
			)
			(layer "F.Fab")
		)
		(fp_line
			(start 0.120396 0.2794)
			(end -0.12065 0.2794)
			(stroke
				(width 0.1)
				(type default)
			)
			(layer "F.Fab")
		)
		(fp_line
			(start 0.120396 0.3048)
			(end 0.120396 0.2794)
			(stroke
				(width 0.1)
				(type default)
			)
			(layer "F.Fab")
		)
		(fp_line
			(start 0.12065 -0.3048)
			(end 0.67945 -0.3048)
			(stroke
				(width 0.1)
				(type default)
			)
			(layer "F.Fab")
		)
		(fp_line
			(start 0.12065 -0.2794)
			(end 0.12065 -0.3048)
			(stroke
				(width 0.1)
				(type default)
			)
			(layer "F.Fab")
		)
		(fp_line
			(start 0.67945 -0.3048)
			(end 0.67945 0.3048)
			(stroke
				(width 0.1)
				(type default)
			)
			(layer "F.Fab")
		)
		(fp_line
			(start 0.67945 0.3048)
			(end 0.120396 0.3048)
			(stroke
				(width 0.1)
				(type default)
			)
			(layer "F.Fab")
		)
		(pad "1" smd circle
			(at -0.40005 0)
			(size 0 0)
			(layers "F.Cu" "F.Mask" "F.Paste")
			(net "P1V8_AUX")
		)
		(pad "2" smd circle
			(at 0.40005 0)
			(size 0 0)
			(layers "F.Cu" "F.Mask" "F.Paste")
			(net "GND")
		)
	)
	(footprint ""
		(layer "F.Cu")
		(at 100.696268 -394.3604 -90)
		(property "Reference" "R749"
			(at 0 0 270)
			(layer "F.SilkS")
			(hide yes)
			(effects
				(font
					(size 1.27 1.27)
				)
			)
		)
		(property "Value" ""
			(at 0 0 270)
			(layer "F.Fab")
			(effects
				(font
					(size 1.27 1.27)
				)
			)
		)
		(duplicate_pad_numbers_are_jumpers no)
		(fp_line
			(start -0.32512 0.175006)
			(end -0.32512 -0.175006)
			(stroke
				(width 0.1)
				(type default)
			)
			(layer "F.Fab")
		)
		(fp_line
			(start 0.32512 0.175006)
			(end -0.32512 0.175006)
			(stroke
				(width 0.1)
				(type default)
			)
			(layer "F.Fab")
		)
		(fp_line
			(start -0.32512 -0.175006)
			(end 0.32512 -0.175006)
			(stroke
				(width 0.1)
				(type default)
			)
			(layer "F.Fab")
		)
		(fp_line
			(start 0.32512 -0.175006)
			(end 0.32512 0.175006)
			(stroke
				(width 0.1)
				(type default)
			)
			(layer "F.Fab")
		)
		(pad "1" smd rect
			(at -0.2667 0 270)
			(size 0.3048 0.381)
			(layers "F.Cu" "F.Mask" "F.Paste")
			(net "RST_RT_CPU1_P1_PERST_R_N")
		)
		(pad "2" smd rect
			(at 0.2667 0 90)
			(size 0.3048 0.381)
			(layers "F.Cu" "F.Mask" "F.Paste")
			(net "GND")
		)
	)
	(footprint ""
		(layer "F.Cu")
		(at 109.210602 -395.782038 90)
		(property "Reference" "R6734"
			(at 0 0 90)
			(layer "F.SilkS")
			(hide yes)
			(effects
				(font
					(size 1.27 1.27)
				)
			)
		)
		(property "Value" ""
			(at 0 0 90)
			(layer "F.Fab")
			(effects
				(font
					(size 1.27 1.27)
				)
			)
		)
		(duplicate_pad_numbers_are_jumpers no)
		(fp_line
			(start 0.32512 -0.175006)
			(end 0.32512 0.175006)
			(stroke
				(width 0.1)
				(type default)
			)
			(layer "F.Fab")
		)
		(fp_line
			(start -0.32512 -0.175006)
			(end 0.32512 -0.175006)
			(stroke
				(width 0.1)
				(type default)
			)
			(layer "F.Fab")
		)
		(fp_line
			(start 0.32512 0.175006)
			(end -0.32512 0.175006)
			(stroke
				(width 0.1)
				(type default)
			)
			(layer "F.Fab")
		)
		(fp_line
			(start -0.32512 0.175006)
			(end -0.32512 -0.175006)
			(stroke
				(width 0.1)
				(type default)
			)
			(layer "F.Fab")
		)
		(pad "1" smd rect
			(at -0.2667 0 90)
			(size 0.3048 0.381)
			(layers "F.Cu" "F.Mask" "F.Paste")
			(net "P1V8_CPU1_RT_1D")
		)
		(pad "2" smd rect
			(at 0.2667 0 270)
			(size 0.3048 0.381)
			(layers "F.Cu" "F.Mask" "F.Paste")
			(net "SMB_RT_CPU1_P1_ROM_R_SCL")
		)
	)
)
